FILE_TYPE = MACRO_DRAWING;
SET COLOR_WIRE YELLOW;
SET COLOR_PROP MONO;
SET COLOR_DOT WHITE;
SET COLOR_ARC YELLOW;
SET COLOR_BODY GREEN;
SET COLOR_NOTE MONO;
SET PROP_DISPLAY VALUE;
SET PAGE_NUMBER P18;
FORCEADD INTEL_CORP_BPAGE..1
(0 0);
FORCEPROP 2 LAST CUSTOM_TXT_CDS <XR_PAGE_TITLE>
J 0
(-7890 5250);
DISPLAY 0.638298 (-7890 5250);
PAINT PINK (-7890 5250);
DISPLAY INVISIBLE (-7890 5250);
FORCEPROP 2 LAST CUSTOM_TXT_CDS <CON_LAST_MODIFIED>
J 0
(-1925 350);
PAINT ORANGE (-1925 350);
FORCEPROP 2 LAST CUSTOM_TXT_CDS <CURRENT_DESIGN_SHEET> OF <TOTAL_DESIGN_SHEETS>
J 0
(-500 25);
PAINT ORANGE (-500 25);
FORCEPROP 1 LAST SCH_ADDRESS3 Santa Clara, CA 95052-8119
J 0
(-3975 25);
DISPLAY 0.617021 (-3975 25);
PAINT GREEN (-3975 25);
FORCEPROP 1 LAST SCH_ADDRESS2 P.O. BOX 58119
J 0
(-3975 75);
DISPLAY 0.617021 (-3975 75);
PAINT GREEN (-3975 75);
FORCEPROP 1 LAST SCH_ADDRESS1 2200 Mission College Blvd.
J 0
(-3975 125);
DISPLAY 0.617021 (-3975 125);
PAINT GREEN (-3975 125);
FORCEPROP 1 LAST SCH_NUMBER H4694802
J 0
(-1300 150);
DISPLAY 1.212766 (-1300 150);
PAINT YELLOW (-1300 150);
FORCEPROP 1 LAST SCH_DEPT BESD
J 1
(-4450 100);
DISPLAY 1.212766 (-4450 100);
PAINT YELLOW (-4450 100);
FORCEPROP 1 LAST SCH_REV 2.420
J 0
(-250 150);
DISPLAY 0.978723 (-250 150);
PAINT YELLOW (-250 150);
FORCEPROP 1 LAST SCH_TITLE FAST_PROCHOT BLOCK DIAGRAM
J 0
(-7950 50);
DISPLAY 1.212766 (-7950 50);
PAINT ORANGE (-7950 50);
FORCEPROP 2 LAST PAGE_BORDER TRUE
J 0
(-7890 5250);
DISPLAY 0.638298 (-7890 5250);
PAINT PINK (-7890 5250);
DISPLAY INVISIBLE (-7890 5250);
FORCEPROP 2 LAST CDS_LIB mstr_symbols
J 0
(0 0);
PAINT MONO (0 0);
DISPLAY INVISIBLE (0 0);
FORCEPROP 1 LAST COMMENT_BODY TRUE
J 0
(12 12);
DISPLAY 0.468085 (12 12);
PAINT GREEN (12 12);
DISPLAY INVISIBLE (12 12);
FORCEPROP 1 LAST CDS_CON_LAST_MODIFIED Tue Dec 01 11:47:59 2015
J 0
(-1425 325);
PAINT ORANGE (-1425 325);
DISPLAY INVISIBLE (-1425 325);
FORCEPROP 2 LAST CDS_XR_PAGE_TITLE CR-18 : @BASEBOARD_FAB2_LIB.BASEBOARD_FAB2(SCH_1):PAGE18
J 0
(-7890 5250);
DISPLAY 0.638298 (-7890 5250);
PAINT PINK (-7890 5250);
DISPLAY INVISIBLE (-7890 5250);
FORCENOTE
$CDS_IMAGE|18_Fast_prochot_topology.jpg|5750|4250
(-4175 2575) 0;
DISPLAY CENTER (-4175 2575);
PAINT MONO (-4175 2575);
QUIT
